(kicad_pcb
	(version 20260206)
	(generator "pcbnew")
	(generator_version "10.0")
	(general
		(thickness 1.6)
		(legacy_teardrops no)
	)
	(paper "A4")
	(title_block
		(title "Wiwynn_Tioga_Pass_MB.brd")
		(comment 1 "Tioga Pass / footprints 1993-1999 of 4770")
	)
	(layers
		(0 "F.Cu" signal "TOP")
		(4 "In1.Cu" signal "L2GND")
		(6 "In2.Cu" signal "L3")
		(8 "In3.Cu" signal "L4GND")
		(10 "In4.Cu" signal "L5")
		(12 "In5.Cu" signal "L6GND")
		(14 "In6.Cu" signal "L7VCC")
		(16 "In7.Cu" signal "L8VCC")
		(18 "In8.Cu" signal "L9GND")
		(20 "In9.Cu" signal "L10")
		(22 "In10.Cu" signal "L11GND")
		(24 "In11.Cu" signal "L12")
		(26 "In12.Cu" signal "L13GND")
		(2 "B.Cu" signal "BOTTOM")
		(9 "F.Adhes" user "F.Adhesive")
		(11 "B.Adhes" user "B.Adhesive")
		(13 "F.Paste" user "Package Geometry/Pastemask Top")
		(15 "B.Paste" user "Package Geometry/Pastemask Bottom")
		(5 "F.SilkS" user "Ref Des/Silkscreen Top")
		(7 "B.SilkS" user "Ref Des/Silkscreen Bottom")
		(1 "F.Mask" user "Board Geometry/Soldermask Top")
		(3 "B.Mask" user "Board Geometry/Soldermask Bottom")
		(17 "Dwgs.User" user "User.Drawings")
		(19 "Cmts.User" user "User.Comments")
		(21 "Eco1.User" user "User.Eco1")
		(23 "Eco2.User" user "User.Eco2")
		(25 "Edge.Cuts" user "Board Geometry/Outline")
		(27 "Margin" user)
		(31 "F.CrtYd" user "Package Geometry/Place Bound Top")
		(29 "B.CrtYd" user "Package Geometry/Place Bound Bottom")
		(35 "F.Fab" user "Ref Des/Assembly Top")
		(33 "B.Fab" user "Ref Des/Assembly Bottom")
	)
	(footprint ""
		(layer "F.Cu")
		(at 173.74108 -65.42278 90)
		(property "Reference" "R4D64"
			(at 0 0 90)
			(layer "F.SilkS")
			(hide yes)
			(effects
				(font
					(size 1.27 1.27)
				)
			)
		)
		(property "Value" ""
			(at 0 0 90)
			(layer "F.Fab")
			(effects
				(font
					(size 1.27 1.27)
				)
			)
		)
		(duplicate_pad_numbers_are_jumpers no)
		(fp_poly
			(pts
				(xy -0.2794 -0.1016) (xy 0.2794 -0.1016) (xy 0.2794 0.9906) (xy -0.2794 0.9906)
			)
			(stroke
				(width 0)
				(type default)
			)
			(fill no)
			(layer "F.CrtYd")
		)
		(fp_line
			(start 0.2794 -0.1016)
			(end -0.2794 -0.1016)
			(stroke
				(width 0.1)
				(type default)
			)
			(layer "F.Fab")
		)
		(fp_line
			(start -0.2794 -0.1016)
			(end -0.2794 0.9906)
			(stroke
				(width 0.1)
				(type default)
			)
			(layer "F.Fab")
		)
		(fp_line
			(start 0.2794 0.9906)
			(end 0.2794 -0.1016)
			(stroke
				(width 0.1)
				(type default)
			)
			(layer "F.Fab")
		)
		(fp_line
			(start -0.2794 0.9906)
			(end 0.2794 0.9906)
			(stroke
				(width 0.1)
				(type default)
			)
			(layer "F.Fab")
		)
		(pad "1" smd rect
			(at 0 0 90)
			(size 0.508 0.508)
			(layers "F.Cu" "F.Mask" "F.Paste")
			(net "VR_PVCCIO_CPU1_XADDR1")
		)
		(pad "2" smd rect
			(at 0 0.889 90)
			(size 0.508 0.508)
			(layers "F.Cu" "F.Mask" "F.Paste")
			(net "GND")
		)
		(zone
			(layer "F.Cu")
			(hatch none 0.5)
			(connect_pads
				(clearance 0)
			)
			(min_thickness 0.25)
			(keepout
				(tracks allowed)
				(vias not_allowed)
				(pads allowed)
				(copperpour not_allowed)
				(footprints allowed)
			)
			(placement
				(enabled no)
				(sheetname "")
			)
			(fill
				(thermal_gap 0.5)
				(thermal_bridge_width 0.5)
				(island_removal_mode 0)
			)
			(polygon
				(pts
					(xy 173.99508 -65.16878) (xy 173.99508 -65.67678) (xy 174.37608 -65.67678) (xy 174.37608 -65.16878)
				)
			)
		)
		(zone
			(layer "F.Cu")
			(hatch none 0.5)
			(connect_pads
				(clearance 0)
			)
			(min_thickness 0.25)
			(keepout
				(tracks not_allowed)
				(vias allowed)
				(pads allowed)
				(copperpour not_allowed)
				(footprints allowed)
			)
			(placement
				(enabled no)
				(sheetname "")
			)
			(fill
				(thermal_gap 0.5)
				(thermal_bridge_width 0.5)
				(island_removal_mode 0)
			)
			(polygon
				(pts
					(xy 174.37608 -65.16878) (xy 174.37608 -65.67678) (xy 173.99508 -65.67678) (xy 173.99508 -65.16878)
				)
			)
		)
	)
	(footprint ""
		(layer "F.Cu")
		(at 23.114 -76.327 -90)
		(property "Reference" "R1D32"
			(at 0 0 270)
			(layer "F.SilkS")
			(hide yes)
			(effects
				(font
					(size 1.27 1.27)
				)
			)
		)
		(property "Value" ""
			(at 0 0 270)
			(layer "F.Fab")
			(effects
				(font
					(size 1.27 1.27)
				)
			)
		)
		(duplicate_pad_numbers_are_jumpers no)
		(fp_poly
			(pts
				(xy -0.2794 -0.1016) (xy 0.2794 -0.1016) (xy 0.2794 0.9906) (xy -0.2794 0.9906)
			)
			(stroke
				(width 0)
				(type default)
			)
			(fill no)
			(layer "F.CrtYd")
		)
		(fp_line
			(start -0.2794 0.9906)
			(end 0.2794 0.9906)
			(stroke
				(width 0.1)
				(type default)
			)
			(layer "F.Fab")
		)
		(fp_line
			(start 0.2794 0.9906)
			(end 0.2794 -0.1016)
			(stroke
				(width 0.1)
				(type default)
			)
			(layer "F.Fab")
		)
		(fp_line
			(start -0.2794 -0.1016)
			(end -0.2794 0.9906)
			(stroke
				(width 0.1)
				(type default)
			)
			(layer "F.Fab")
		)
		(fp_line
			(start 0.2794 -0.1016)
			(end -0.2794 -0.1016)
			(stroke
				(width 0.1)
				(type default)
			)
			(layer "F.Fab")
		)
		(pad "1" smd rect
			(at 0 0 270)
			(size 0.508 0.508)
			(layers "F.Cu" "F.Mask" "F.Paste")
			(net "A_HSC_VCAP")
		)
		(pad "2" smd rect
			(at 0 0.889 270)
			(size 0.508 0.508)
			(layers "F.Cu" "F.Mask" "F.Paste")
			(net "A_HSC_ISTART")
		)
		(zone
			(layer "F.Cu")
			(hatch none 0.5)
			(connect_pads
				(clearance 0)
			)
			(min_thickness 0.25)
			(keepout
				(tracks not_allowed)
				(vias allowed)
				(pads allowed)
				(copperpour not_allowed)
				(footprints allowed)
			)
			(placement
				(enabled no)
				(sheetname "")
			)
			(fill
				(thermal_gap 0.5)
				(thermal_bridge_width 0.5)
				(island_removal_mode 0)
			)
			(polygon
				(pts
					(xy 22.479 -76.581) (xy 22.479 -76.073) (xy 22.86 -76.073) (xy 22.86 -76.581)
				)
			)
		)
		(zone
			(layer "F.Cu")
			(hatch none 0.5)
			(connect_pads
				(clearance 0)
			)
			(min_thickness 0.25)
			(keepout
				(tracks allowed)
				(vias not_allowed)
				(pads allowed)
				(copperpour not_allowed)
				(footprints allowed)
			)
			(placement
				(enabled no)
				(sheetname "")
			)
			(fill
				(thermal_gap 0.5)
				(thermal_bridge_width 0.5)
				(island_removal_mode 0)
			)
			(polygon
				(pts
					(xy 22.86 -76.581) (xy 22.86 -76.073) (xy 22.479 -76.073) (xy 22.479 -76.581)
				)
			)
		)
	)
	(footprint ""
		(layer "F.Cu")
		(at 101.448616 -164.9857 90)
		(property "Reference" "T1D9"
			(at 0 0 90)
			(layer "F.SilkS")
			(hide yes)
			(effects
				(font
					(size 1.27 1.27)
				)
			)
		)
		(property "Value" "*"
			(at -3.4036 -4.46405 90)
			(unlocked yes)
			(layer "F.Fab")
			(hide yes)
			(effects
				(font
					(size 0.889 0.889)
					(thickness 0.1524)
				)
			)
		)
		(property "Device Type" "TEST-PAD-12P-1-GP-U_DISCRET-GBA"
			(at -3.4036 -5.98805 90)
			(unlocked yes)
			(layer "F.Fab")
			(hide yes)
			(effects
				(font
					(size 0.889 0.889)
					(thickness 0.1524)
				)
			)
		)
		(duplicate_pad_numbers_are_jumpers no)
		(fp_line
			(start 2.3622 -4.826)
			(end 2.3622 3.4798)
			(stroke
				(width 0.1524)
				(type default)
			)
			(layer "F.SilkS")
		)
		(fp_line
			(start -2.3876 -4.826)
			(end 2.3622 -4.826)
			(stroke
				(width 0.1524)
				(type default)
			)
			(layer "F.SilkS")
		)
		(fp_line
			(start 2.3622 3.4798)
			(end -2.3876 3.4798)
			(stroke
				(width 0.1524)
				(type default)
			)
			(layer "F.SilkS")
		)
		(fp_line
			(start -2.3876 3.4798)
			(end -2.3876 -4.826)
			(stroke
				(width 0.1524)
				(type default)
			)
			(layer "F.SilkS")
		)
		(fp_rect
			(start -2.6416 3.7338)
			(end 2.6162 -5.08)
			(stroke
				(width 0)
				(type default)
			)
			(fill no)
			(layer "F.CrtYd")
		)
		(fp_rect
			(start -2.6416 3.7338)
			(end 2.6162 -5.08)
			(stroke
				(width 0)
				(type default)
			)
			(fill no)
			(layer "F.Fab")
		)
		(pad "1" smd circle
			(at 0.496824 -1.301496 90)
			(size 0.6604 0.6604)
			(layers "F.Cu" "F.Mask" "F.Paste")
			(net "L12_85OHM_5INCH_DP")
		)
		(pad "2" smd circle
			(at -0.503936 -1.301496 90)
			(size 0.6604 0.6604)
			(layers "F.Cu" "F.Mask" "F.Paste")
			(net "L12_85OHM_5INCH_DN")
		)
		(pad "3" smd custom
			(at -0.00889 0.370078 90)
			(size 0.74295 0.74295)
			(layers "F.Cu" "F.Mask" "F.Paste")
			(net "GND")
			(options
				(clearance outline)
				(anchor circle)
			)
			(primitives
				(gr_poly
					(pts
						(xy -2.1209 1.4859) (xy 2.1209 1.4859) (xy 2.1209 -1.4859) (xy 1.08585 -1.4859) (xy 1.08585 -0.4699)
						(xy -1.08585 -0.4699) (xy -1.08585 -1.4859) (xy -2.1209 -1.4859)
					)
					(width 0)
					(fill yes)
				)
			)
		)
		(pad "4" thru_hole circle
			(at 1.266444 -3.851656 90)
			(size 1.4478 1.4478)
			(drill 1.0414)
			(layers "*.Cu" "*.Mask")
			(remove_unused_layers no)
			(net "GND")
			(clearance 0.1524)
			(thermal_gap 0.1524)
		)
		(pad "5" thru_hole circle
			(at -1.273556 -3.851656 90)
			(size 1.4478 1.4478)
			(drill 1.0414)
			(layers "*.Cu" "*.Mask")
			(remove_unused_layers no)
			(net "GND")
			(clearance 0.1524)
			(thermal_gap 0.1524)
		)
		(pad "6" thru_hole circle
			(at 1.266444 2.498344 90)
			(size 1.4478 1.4478)
			(drill 1.0414)
			(layers "*.Cu" "*.Mask")
			(remove_unused_layers no)
			(net "GND")
			(clearance 0.1524)
			(thermal_gap 0.1524)
		)
		(pad "7" thru_hole circle
			(at -1.273556 2.498344 90)
			(size 1.4478 1.4478)
			(drill 1.0414)
			(layers "*.Cu" "*.Mask")
			(remove_unused_layers no)
			(net "GND")
			(clearance 0.1524)
			(thermal_gap 0.1524)
		)
		(pad "8" thru_hole circle
			(at 1.27 -0.4572 90)
			(size 0.7112 0.7112)
			(drill 0.4064)
			(layers "*.Cu" "*.Mask")
			(remove_unused_layers no)
			(net "GND")
			(clearance 0.1016)
			(thermal_gap 0.1016)
		)
		(pad "9" thru_hole circle
			(at 1.27 0.762 90)
			(size 0.7112 0.7112)
			(drill 0.4064)
			(layers "*.Cu" "*.Mask")
			(remove_unused_layers no)
			(net "GND")
			(clearance 0.1016)
			(thermal_gap 0.1016)
		)
		(pad "10" thru_hole circle
			(at -0.0254 0.762 90)
			(size 0.7112 0.7112)
			(drill 0.4064)
			(layers "*.Cu" "*.Mask")
			(remove_unused_layers no)
			(net "GND")
			(clearance 0.1016)
			(thermal_gap 0.1016)
		)
		(pad "11" thru_hole circle
			(at -1.27 0.762 90)
			(size 0.7112 0.7112)
			(drill 0.4064)
			(layers "*.Cu" "*.Mask")
			(remove_unused_layers no)
			(net "GND")
			(clearance 0.1016)
			(thermal_gap 0.1016)
		)
		(pad "12" thru_hole circle
			(at -1.27 -0.4572 90)
			(size 0.7112 0.7112)
			(drill 0.4064)
			(layers "*.Cu" "*.Mask")
			(remove_unused_layers no)
			(net "GND")
			(clearance 0.1016)
			(thermal_gap 0.1016)
		)
	)
	(footprint ""
		(layer "F.Cu")
		(at 393.192 -71.0565 180)
		(property "Reference" "R7E15"
			(at 0 0 180)
			(layer "F.SilkS")
			(hide yes)
			(effects
				(font
					(size 1.27 1.27)
				)
			)
		)
		(property "Value" ""
			(at 0 0 180)
			(layer "F.Fab")
			(effects
				(font
					(size 1.27 1.27)
				)
			)
		)
		(duplicate_pad_numbers_are_jumpers no)
		(fp_poly
			(pts
				(xy -0.2794 -0.1016) (xy 0.2794 -0.1016) (xy 0.2794 0.9906) (xy -0.2794 0.9906)
			)
			(stroke
				(width 0)
				(type default)
			)
			(fill no)
			(layer "F.CrtYd")
		)
		(fp_line
			(start 0.2794 0.9906)
			(end 0.2794 -0.1016)
			(stroke
				(width 0.1)
				(type default)
			)
			(layer "F.Fab")
		)
		(fp_line
			(start 0.2794 -0.1016)
			(end -0.2794 -0.1016)
			(stroke
				(width 0.1)
				(type default)
			)
			(layer "F.Fab")
		)
		(fp_line
			(start -0.2794 0.9906)
			(end 0.2794 0.9906)
			(stroke
				(width 0.1)
				(type default)
			)
			(layer "F.Fab")
		)
		(fp_line
			(start -0.2794 -0.1016)
			(end -0.2794 0.9906)
			(stroke
				(width 0.1)
				(type default)
			)
			(layer "F.Fab")
		)
		(pad "1" smd rect
			(at 0 0 180)
			(size 0.508 0.508)
			(layers "F.Cu" "F.Mask" "F.Paste")
			(net "PWRGD_P5V_STBY_R")
		)
		(pad "2" smd rect
			(at 0 0.889 180)
			(size 0.508 0.508)
			(layers "F.Cu" "F.Mask" "F.Paste")
			(net "PWRGD_P5V_STBY")
		)
		(zone
			(layer "F.Cu")
			(hatch none 0.5)
			(connect_pads
				(clearance 0)
			)
			(min_thickness 0.25)
			(keepout
				(tracks not_allowed)
				(vias allowed)
				(pads allowed)
				(copperpour not_allowed)
				(footprints allowed)
			)
			(placement
				(enabled no)
				(sheetname "")
			)
			(fill
				(thermal_gap 0.5)
				(thermal_bridge_width 0.5)
				(island_removal_mode 0)
			)
			(polygon
				(pts
					(xy 393.446 -71.6915) (xy 392.938 -71.6915) (xy 392.938 -71.3105) (xy 393.446 -71.3105)
				)
			)
		)
		(zone
			(layer "F.Cu")
			(hatch none 0.5)
			(connect_pads
				(clearance 0)
			)
			(min_thickness 0.25)
			(keepout
				(tracks allowed)
				(vias not_allowed)
				(pads allowed)
				(copperpour not_allowed)
				(footprints allowed)
			)
			(placement
				(enabled no)
				(sheetname "")
			)
			(fill
				(thermal_gap 0.5)
				(thermal_bridge_width 0.5)
				(island_removal_mode 0)
			)
			(polygon
				(pts
					(xy 393.446 -71.3105) (xy 392.938 -71.3105) (xy 392.938 -71.6915) (xy 393.446 -71.6915)
				)
			)
		)
	)
	(footprint ""
		(layer "F.Cu")
		(at 269.559532 -149.8092 90)
		(property "Reference" "C5A7"
			(at 1.848866 0.752348 90)
			(unlocked yes)
			(layer "F.SilkS")
			(effects
				(font
					(size 1.27 0.9652)
					(thickness 0.1524)
				)
			)
		)
		(property "Value" ""
			(at 0 0 90)
			(layer "F.Fab")
			(effects
				(font
					(size 1.27 1.27)
				)
			)
		)
		(duplicate_pad_numbers_are_jumpers no)
		(fp_rect
			(start -0.500126 1.598422)
			(end 0.500126 -0.201422)
			(stroke
				(width 0)
				(type default)
			)
			(fill no)
			(layer "F.CrtYd")
		)
		(fp_line
			(start 0.500126 -0.201422)
			(end 0.500126 1.598422)
			(stroke
				(width 0.1)
				(type default)
			)
			(layer "F.Fab")
		)
		(fp_line
			(start -0.500126 -0.201422)
			(end 0.500126 -0.201422)
			(stroke
				(width 0.1)
				(type default)
			)
			(layer "F.Fab")
		)
		(fp_line
			(start 0.500126 1.598422)
			(end -0.500126 1.598422)
			(stroke
				(width 0.1)
				(type default)
			)
			(layer "F.Fab")
		)
		(fp_line
			(start -0.500126 1.598422)
			(end -0.500126 -0.201422)
			(stroke
				(width 0.1)
				(type default)
			)
			(layer "F.Fab")
		)
		(pad "1" smd rect
			(at 0 0)
			(size 0.889 0.9906)
			(layers "F.Cu" "F.Mask" "F.Paste")
			(net "PVDDQ_DEF")
		)
		(pad "2" smd rect
			(at 0 1.397)
			(size 0.889 0.9906)
			(layers "F.Cu" "F.Mask" "F.Paste")
			(net "GND")
		)
		(zone
			(layer "F.Cu")
			(hatch none 0.5)
			(connect_pads
				(clearance 0)
			)
			(min_thickness 0.25)
			(keepout
				(tracks allowed)
				(vias not_allowed)
				(pads allowed)
				(copperpour not_allowed)
				(footprints allowed)
			)
			(placement
				(enabled no)
				(sheetname "")
			)
			(fill
				(thermal_gap 0.5)
				(thermal_bridge_width 0.5)
				(island_removal_mode 0)
			)
			(polygon
				(pts
					(xy 270.512032 -149.3139) (xy 270.512032 -150.3045) (xy 270.004032 -150.3045) (xy 270.004032 -149.3139)
				)
			)
		)
		(zone
			(layer "F.Cu")
			(hatch none 0.5)
			(connect_pads
				(clearance 0)
			)
			(min_thickness 0.25)
			(keepout
				(tracks not_allowed)
				(vias allowed)
				(pads allowed)
				(copperpour not_allowed)
				(footprints allowed)
			)
			(placement
				(enabled no)
				(sheetname "")
			)
			(fill
				(thermal_gap 0.5)
				(thermal_bridge_width 0.5)
				(island_removal_mode 0)
			)
			(polygon
				(pts
					(xy 270.512032 -149.3139) (xy 270.512032 -150.3045) (xy 270.004032 -150.3045) (xy 270.004032 -149.3139)
				)
			)
		)
	)
	(footprint ""
		(layer "F.Cu")
		(at 191.897 -13.3985)
		(property "Reference" "C4G1"
			(at 0 0 0)
			(layer "F.SilkS")
			(hide yes)
			(effects
				(font
					(size 1.27 1.27)
				)
			)
		)
		(property "Value" ""
			(at 0 0 0)
			(layer "F.Fab")
			(effects
				(font
					(size 1.27 1.27)
				)
			)
		)
		(duplicate_pad_numbers_are_jumpers no)
		(fp_poly
			(pts
				(xy 0.3048 -0.1016) (xy 0.3048 0.9906) (xy -0.3048 0.9906) (xy -0.3048 -0.1016)
			)
			(stroke
				(width 0)
				(type default)
			)
			(fill no)
			(layer "F.CrtYd")
		)
		(fp_line
			(start -0.3048 -0.1016)
			(end -0.3048 0.9906)
			(stroke
				(width 0.1)
				(type default)
			)
			(layer "F.Fab")
		)
		(fp_line
			(start -0.3048 0.9906)
			(end 0.3048 0.9906)
			(stroke
				(width 0.1)
				(type default)
			)
			(layer "F.Fab")
		)
		(fp_line
			(start 0.3048 -0.1016)
			(end -0.3048 -0.1016)
			(stroke
				(width 0.1)
				(type default)
			)
			(layer "F.Fab")
		)
		(fp_line
			(start 0.3048 0.9906)
			(end 0.3048 -0.1016)
			(stroke
				(width 0.1)
				(type default)
			)
			(layer "F.Fab")
		)
		(pad "1" smd rect
			(at 0 0)
			(size 0.508 0.508)
			(layers "F.Cu" "F.Mask" "F.Paste")
			(net "M_B_CPU_VREF")
		)
		(pad "2" smd rect
			(at 0 0.889)
			(size 0.508 0.508)
			(layers "F.Cu" "F.Mask" "F.Paste")
			(net "GND")
		)
		(zone
			(layer "F.Cu")
			(hatch none 0.5)
			(connect_pads
				(clearance 0)
			)
			(min_thickness 0.25)
			(keepout
				(tracks allowed)
				(vias not_allowed)
				(pads allowed)
				(copperpour not_allowed)
				(footprints allowed)
			)
			(placement
				(enabled no)
				(sheetname "")
			)
			(fill
				(thermal_gap 0.5)
				(thermal_bridge_width 0.5)
				(island_removal_mode 0)
			)
			(polygon
				(pts
					(xy 191.643 -13.1445) (xy 192.151 -13.1445) (xy 192.151 -12.7635) (xy 191.643 -12.7635)
				)
			)
		)
		(zone
			(layer "F.Cu")
			(hatch none 0.5)
			(connect_pads
				(clearance 0)
			)
			(min_thickness 0.25)
			(keepout
				(tracks not_allowed)
				(vias allowed)
				(pads allowed)
				(copperpour not_allowed)
				(footprints allowed)
			)
			(placement
				(enabled no)
				(sheetname "")
			)
			(fill
				(thermal_gap 0.5)
				(thermal_bridge_width 0.5)
				(island_removal_mode 0)
			)
			(polygon
				(pts
					(xy 191.643 -12.7635) (xy 192.151 -12.7635) (xy 192.151 -13.1445) (xy 191.643 -13.1445)
				)
			)
		)
	)
	(footprint ""
		(layer "F.Cu")
		(at 110.0074 -83.8962)
		(property "Reference" "R3D1"
			(at 0 0 0)
			(layer "F.SilkS")
			(hide yes)
			(effects
				(font
					(size 1.27 1.27)
				)
			)
		)
		(property "Value" ""
			(at 0 0 0)
			(layer "F.Fab")
			(effects
				(font
					(size 1.27 1.27)
				)
			)
		)
		(duplicate_pad_numbers_are_jumpers no)
		(fp_poly
			(pts
				(xy -0.2794 -0.1016) (xy 0.2794 -0.1016) (xy 0.2794 0.9906) (xy -0.2794 0.9906)
			)
			(stroke
				(width 0)
				(type default)
			)
			(fill no)
			(layer "F.CrtYd")
		)
		(fp_line
			(start -0.2794 -0.1016)
			(end -0.2794 0.9906)
			(stroke
				(width 0.1)
				(type default)
			)
			(layer "F.Fab")
		)
		(fp_line
			(start -0.2794 0.9906)
			(end 0.2794 0.9906)
			(stroke
				(width 0.1)
				(type default)
			)
			(layer "F.Fab")
		)
		(fp_line
			(start 0.2794 -0.1016)
			(end -0.2794 -0.1016)
			(stroke
				(width 0.1)
				(type default)
			)
			(layer "F.Fab")
		)
		(fp_line
			(start 0.2794 0.9906)
			(end 0.2794 -0.1016)
			(stroke
				(width 0.1)
				(type default)
			)
			(layer "F.Fab")
		)
		(pad "1" smd rect
			(at 0 0)
			(size 0.508 0.508)
			(layers "F.Cu" "F.Mask" "F.Paste")
			(net "A_CPU1_KLM_RCOMP0")
		)
		(pad "2" smd rect
			(at 0 0.889)
			(size 0.508 0.508)
			(layers "F.Cu" "F.Mask" "F.Paste")
			(net "GND")
		)
		(zone
			(layer "F.Cu")
			(hatch none 0.5)
			(connect_pads
				(clearance 0)
			)
			(min_thickness 0.25)
			(keepout
				(tracks allowed)
				(vias not_allowed)
				(pads allowed)
				(copperpour not_allowed)
				(footprints allowed)
			)
			(placement
				(enabled no)
				(sheetname "")
			)
			(fill
				(thermal_gap 0.5)
				(thermal_bridge_width 0.5)
				(island_removal_mode 0)
			)
			(polygon
				(pts
					(xy 109.7534 -83.6422) (xy 110.2614 -83.6422) (xy 110.2614 -83.2612) (xy 109.7534 -83.2612)
				)
			)
		)
		(zone
			(layer "F.Cu")
			(hatch none 0.5)
			(connect_pads
				(clearance 0)
			)
			(min_thickness 0.25)
			(keepout
				(tracks not_allowed)
				(vias allowed)
				(pads allowed)
				(copperpour not_allowed)
				(footprints allowed)
			)
			(placement
				(enabled no)
				(sheetname "")
			)
			(fill
				(thermal_gap 0.5)
				(thermal_bridge_width 0.5)
				(island_removal_mode 0)
			)
			(polygon
				(pts
					(xy 109.7534 -83.2612) (xy 110.2614 -83.2612) (xy 110.2614 -83.6422) (xy 109.7534 -83.6422)
				)
			)
		)
	)
)
